(kicad_pcb
	(version 20260206)
	(generator "pcbnew")
	(generator_version "10.0")
	(general
		(thickness 1.6)
		(legacy_teardrops no)
	)
	(paper "A4")
	(title_block
		(title "baseboard — 13948-1b.1110WZS1818.brd")
		(comment 1 "Honey Badger (Wiwynn) / footprints 347-353 of 2523")
	)
	(layers
		(0 "F.Cu" signal "TOP")
		(4 "In1.Cu" signal "L2GND")
		(6 "In2.Cu" signal "L3")
		(8 "In3.Cu" signal "L4VCC")
		(10 "In4.Cu" signal "L5VCC")
		(12 "In5.Cu" signal "L6")
		(14 "In6.Cu" signal "L7GND")
		(2 "B.Cu" signal "BOTTOM")
		(9 "F.Adhes" user "F.Adhesive")
		(11 "B.Adhes" user "B.Adhesive")
		(13 "F.Paste" user "Package Geometry/Pastemask Top")
		(15 "B.Paste" user "Package Geometry/Pastemask Bottom")
		(5 "F.SilkS" user "Ref Des/Silkscreen Top")
		(7 "B.SilkS" user "Ref Des/Silkscreen Bottom")
		(1 "F.Mask" user "Board Geometry/Soldermask Top")
		(3 "B.Mask" user "Board Geometry/Soldermask Bottom")
		(17 "Dwgs.User" user "User.Drawings")
		(19 "Cmts.User" user "User.Comments")
		(21 "Eco1.User" user "User.Eco1")
		(23 "Eco2.User" user "User.Eco2")
		(25 "Edge.Cuts" user "Board Geometry/Outline")
		(27 "Margin" user)
		(31 "F.CrtYd" user "Package Geometry/Place Bound Top")
		(29 "B.CrtYd" user "Package Geometry/Place Bound Bottom")
		(35 "F.Fab" user "Ref Des/Assembly Top")
		(33 "B.Fab" user "Ref Des/Assembly Bottom")
	)
	(footprint ""
		(layer "F.Cu")
		(at 48.4632 -119.0752)
		(property "Reference" "SC1298"
			(at 0 0 0)
			(layer "F.SilkS")
			(hide yes)
			(effects
				(font
					(size 1.27 1.27)
				)
			)
		)
		(property "Value" "SCD1U16V2KX-3GP"
			(at 1.1811 -2.7051 0)
			(unlocked yes)
			(layer "F.Fab")
			(hide yes)
			(effects
				(font
					(size 1.016 1.016)
					(thickness 0.1524)
				)
			)
		)
		(property "Device Type" "C402H22"
			(at 1.1811 -4.2291 0)
			(unlocked yes)
			(layer "F.Fab")
			(hide yes)
			(effects
				(font
					(size 1.016 1.016)
					(thickness 0.1524)
				)
			)
		)
		(duplicate_pad_numbers_are_jumpers no)
		(fp_rect
			(start -0.4318 0.9525)
			(end 0.4318 -0.9525)
			(stroke
				(width 0)
				(type default)
			)
			(fill no)
			(layer "F.CrtYd")
		)
		(fp_rect
			(start -0.4318 0.9525)
			(end 0.4318 -0.9525)
			(stroke
				(width 0)
				(type default)
			)
			(fill no)
			(layer "F.Fab")
		)
		(pad "1" smd custom
			(at 0 -0.4445)
			(size 0.1524 0.1524)
			(layers "F.Cu" "F.Mask" "F.Paste")
			(net "P1V8_E")
			(options
				(clearance outline)
				(anchor circle)
			)
			(primitives
				(gr_poly
					(pts
						(arc
							(start 0.3048 -0.2032)
							(mid 0.275042 -0.275042)
							(end 0.2032 -0.3048)
						)
						(arc
							(start -0.2032 -0.3048)
							(mid -0.275042 -0.275042)
							(end -0.3048 -0.2032)
						)
						(arc
							(start -0.3048 0.2032)
							(mid -0.275042 0.275042)
							(end -0.2032 0.3048)
						)
						(arc
							(start 0.2032 0.3048)
							(mid 0.275042 0.275042)
							(end 0.3048 0.2032)
						)
					)
					(width 0)
					(fill yes)
				)
			)
		)
		(pad "2" smd custom
			(at 0 0.4445)
			(size 0.1524 0.1524)
			(layers "F.Cu" "F.Mask" "F.Paste")
			(net "GND")
			(options
				(clearance outline)
				(anchor circle)
			)
			(primitives
				(gr_poly
					(pts
						(arc
							(start 0.3048 -0.2032)
							(mid 0.275042 -0.275042)
							(end 0.2032 -0.3048)
						)
						(arc
							(start -0.2032 -0.3048)
							(mid -0.275042 -0.275042)
							(end -0.3048 -0.2032)
						)
						(arc
							(start -0.3048 0.2032)
							(mid -0.275042 0.275042)
							(end -0.2032 0.3048)
						)
						(arc
							(start 0.2032 0.3048)
							(mid 0.275042 0.275042)
							(end 0.3048 0.2032)
						)
					)
					(width 0)
					(fill yes)
				)
			)
		)
	)
	(footprint ""
		(layer "F.Cu")
		(at 161.925 -115.062 -90)
		(property "Reference" "PR156"
			(at 0 0 270)
			(layer "F.SilkS")
			(hide yes)
			(effects
				(font
					(size 1.27 1.27)
				)
			)
		)
		(property "Value" "10D7R2F-GP"
			(at 0.064008 -3.993896 270)
			(unlocked yes)
			(layer "F.Fab")
			(hide yes)
			(effects
				(font
					(size 1.016 1.016)
					(thickness 0.1524)
				)
			)
		)
		(property "Device Type" "R402H16"
			(at 0.064008 -5.517896 270)
			(unlocked yes)
			(layer "F.Fab")
			(hide yes)
			(effects
				(font
					(size 1.016 1.016)
					(thickness 0.1524)
				)
			)
		)
		(duplicate_pad_numbers_are_jumpers no)
		(fp_line
			(start -0.508 -0.9398)
			(end -0.508 0.9398)
			(stroke
				(width 0.1524)
				(type default)
			)
			(layer "F.SilkS")
		)
		(fp_line
			(start 0.508 -0.9398)
			(end -0.508 -0.9398)
			(stroke
				(width 0.1524)
				(type default)
			)
			(layer "F.SilkS")
		)
		(fp_rect
			(start -0.508 0.9398)
			(end 0.508 -0.9398)
			(stroke
				(width 0)
				(type default)
			)
			(fill no)
			(layer "F.CrtYd")
		)
		(fp_rect
			(start -0.508 0.9398)
			(end 0.508 -0.9398)
			(stroke
				(width 0)
				(type default)
			)
			(fill no)
			(layer "F.Fab")
		)
		(pad "1" smd custom
			(at 0 -0.4445 270)
			(size 0.1397 0.1397)
			(layers "F.Cu" "F.Mask" "F.Paste")
			(net "P0V9_E_VFB_R")
			(options
				(clearance outline)
				(anchor circle)
			)
			(primitives
				(gr_poly
					(pts
						(arc
							(start -0.1778 -0.2794)
							(mid -0.249642 -0.249642)
							(end -0.2794 -0.1778)
						)
						(arc
							(start -0.2794 0.1778)
							(mid -0.249642 0.249642)
							(end -0.1778 0.2794)
						)
						(arc
							(start 0.1778 0.2794)
							(mid 0.249642 0.249642)
							(end 0.2794 0.1778)
						)
						(arc
							(start 0.2794 -0.1778)
							(mid 0.249642 -0.249642)
							(end 0.1778 -0.2794)
						)
					)
					(width 0)
					(fill yes)
				)
			)
		)
		(pad "2" smd custom
			(at 0 0.4445 270)
			(size 0.1397 0.1397)
			(layers "F.Cu" "F.Mask" "F.Paste")
			(net "P0V9_E")
			(options
				(clearance outline)
				(anchor circle)
			)
			(primitives
				(gr_poly
					(pts
						(arc
							(start -0.1778 -0.2794)
							(mid -0.249642 -0.249642)
							(end -0.2794 -0.1778)
						)
						(arc
							(start -0.2794 0.1778)
							(mid -0.249642 0.249642)
							(end -0.1778 0.2794)
						)
						(arc
							(start 0.1778 0.2794)
							(mid 0.249642 0.249642)
							(end 0.2794 0.1778)
						)
						(arc
							(start 0.2794 -0.1778)
							(mid 0.249642 -0.249642)
							(end 0.1778 -0.2794)
						)
					)
					(width 0)
					(fill yes)
				)
			)
		)
	)
	(footprint ""
		(layer "F.Cu")
		(at 191.389 -117.221 -90)
		(property "Reference" "PQ6"
			(at 0 0 270)
			(layer "F.SilkS")
			(hide yes)
			(effects
				(font
					(size 1.27 1.27)
				)
			)
		)
		(property "Value" "2N7002A-7-GP"
			(at 0.127 -8.9662 270)
			(unlocked yes)
			(layer "F.Fab")
			(hide yes)
			(effects
				(font
					(size 1.016 1.016)
					(thickness 0.1524)
				)
			)
		)
		(property "Device Type" "SOT23DGS2D4H48"
			(at 0.127 -10.4902 270)
			(unlocked yes)
			(layer "F.Fab")
			(hide yes)
			(effects
				(font
					(size 1.016 1.016)
					(thickness 0.1524)
				)
			)
		)
		(duplicate_pad_numbers_are_jumpers no)
		(fp_line
			(start -1.651 1.778)
			(end 1.651 1.778)
			(stroke
				(width 0.1524)
				(type default)
			)
			(layer "F.SilkS")
		)
		(fp_line
			(start 1.651 1.778)
			(end 1.651 -1.778)
			(stroke
				(width 0.1524)
				(type default)
			)
			(layer "F.SilkS")
		)
		(fp_line
			(start -1.651 -1.778)
			(end -1.651 1.778)
			(stroke
				(width 0.1524)
				(type default)
			)
			(layer "F.SilkS")
		)
		(fp_line
			(start 1.651 -1.778)
			(end -1.651 -1.778)
			(stroke
				(width 0.1524)
				(type default)
			)
			(layer "F.SilkS")
		)
		(fp_poly
			(pts
				(xy -1.778 1.8796) (xy -1.778 -1.8796) (xy 1.778 -1.8796) (xy 1.778 1.8796)
			)
			(stroke
				(width 0)
				(type default)
			)
			(fill no)
			(layer "F.CrtYd")
		)
		(fp_poly
			(pts
				(xy -1.778 1.8796) (xy -1.778 -1.8796) (xy 1.778 -1.8796) (xy 1.778 1.8796)
			)
			(stroke
				(width 0)
				(type default)
			)
			(fill no)
			(layer "F.Fab")
		)
		(pad "D" smd custom
			(at 0 -0.9525 270)
			(size 0.1905 0.1905)
			(layers "F.Cu" "F.Mask" "F.Paste")
			(net "P1V8_PG_R_1")
			(options
				(clearance outline)
				(anchor circle)
			)
			(primitives
				(gr_poly
					(pts
						(arc
							(start -0.1778 0.5715)
							(mid -0.321484 0.511984)
							(end -0.381 0.3683)
						)
						(arc
							(start -0.381 -0.3683)
							(mid -0.321484 -0.511984)
							(end -0.1778 -0.5715)
						)
						(arc
							(start 0.1778 -0.5715)
							(mid 0.321484 -0.511984)
							(end 0.381 -0.3683)
						)
						(arc
							(start 0.381 0.3683)
							(mid 0.321484 0.511984)
							(end 0.1778 0.5715)
						)
					)
					(width 0)
					(fill yes)
				)
			)
		)
		(pad "G" smd custom
			(at -0.98425 0.9525 270)
			(size 0.1905 0.1905)
			(layers "F.Cu" "F.Mask" "F.Paste")
			(net "P3V3_STBY_B2")
			(options
				(clearance outline)
				(anchor circle)
			)
			(primitives
				(gr_poly
					(pts
						(arc
							(start -0.1778 0.5715)
							(mid -0.321484 0.511984)
							(end -0.381 0.3683)
						)
						(arc
							(start -0.381 -0.3683)
							(mid -0.321484 -0.511984)
							(end -0.1778 -0.5715)
						)
						(arc
							(start 0.1778 -0.5715)
							(mid 0.321484 -0.511984)
							(end 0.381 -0.3683)
						)
						(arc
							(start 0.381 0.3683)
							(mid 0.321484 0.511984)
							(end 0.1778 0.5715)
						)
					)
					(width 0)
					(fill yes)
				)
			)
		)
		(pad "S" smd custom
			(at 0.98425 0.9525 270)
			(size 0.1905 0.1905)
			(layers "F.Cu" "F.Mask" "F.Paste")
			(net "GND")
			(options
				(clearance outline)
				(anchor circle)
			)
			(primitives
				(gr_poly
					(pts
						(arc
							(start -0.1778 0.5715)
							(mid -0.321484 0.511984)
							(end -0.381 0.3683)
						)
						(arc
							(start -0.381 -0.3683)
							(mid -0.321484 -0.511984)
							(end -0.1778 -0.5715)
						)
						(arc
							(start 0.1778 -0.5715)
							(mid 0.321484 -0.511984)
							(end 0.381 -0.3683)
						)
						(arc
							(start 0.381 0.3683)
							(mid 0.321484 0.511984)
							(end 0.1778 0.5715)
						)
					)
					(width 0)
					(fill yes)
				)
			)
		)
	)
	(footprint ""
		(layer "F.Cu")
		(at 318.008 -170.434 90)
		(property "Reference" "R336"
			(at 0 0 90)
			(layer "F.SilkS")
			(hide yes)
			(effects
				(font
					(size 1.27 1.27)
				)
			)
		)
		(property "Value" "0R2J-2-GP"
			(at 0.064008 -3.993896 90)
			(unlocked yes)
			(layer "F.Fab")
			(hide yes)
			(effects
				(font
					(size 1.016 1.016)
					(thickness 0.1524)
				)
			)
		)
		(property "Device Type" "R402H16"
			(at 0.064008 -5.517896 90)
			(unlocked yes)
			(layer "F.Fab")
			(hide yes)
			(effects
				(font
					(size 1.016 1.016)
					(thickness 0.1524)
				)
			)
		)
		(duplicate_pad_numbers_are_jumpers no)
		(fp_line
			(start 0.508 -0.9398)
			(end -0.508 -0.9398)
			(stroke
				(width 0.1524)
				(type default)
			)
			(layer "F.SilkS")
		)
		(fp_line
			(start -0.508 -0.9398)
			(end -0.508 0.9398)
			(stroke
				(width 0.1524)
				(type default)
			)
			(layer "F.SilkS")
		)
		(fp_rect
			(start -0.508 0.9398)
			(end 0.508 -0.9398)
			(stroke
				(width 0)
				(type default)
			)
			(fill no)
			(layer "F.CrtYd")
		)
		(fp_rect
			(start -0.508 0.9398)
			(end 0.508 -0.9398)
			(stroke
				(width 0)
				(type default)
			)
			(fill no)
			(layer "F.Fab")
		)
		(pad "1" smd custom
			(at 0 -0.4445 90)
			(size 0.1397 0.1397)
			(layers "F.Cu" "F.Mask" "F.Paste")
			(net "JTAG_BMC_TRST_N")
			(options
				(clearance outline)
				(anchor circle)
			)
			(primitives
				(gr_poly
					(pts
						(arc
							(start -0.1778 -0.2794)
							(mid -0.249642 -0.249642)
							(end -0.2794 -0.1778)
						)
						(arc
							(start -0.2794 0.1778)
							(mid -0.249642 0.249642)
							(end -0.1778 0.2794)
						)
						(arc
							(start 0.1778 0.2794)
							(mid 0.249642 0.249642)
							(end 0.2794 0.1778)
						)
						(arc
							(start 0.2794 -0.1778)
							(mid 0.249642 -0.249642)
							(end 0.1778 -0.2794)
						)
					)
					(width 0)
					(fill yes)
				)
			)
		)
		(pad "2" smd custom
			(at 0 0.4445 90)
			(size 0.1397 0.1397)
			(layers "F.Cu" "F.Mask" "F.Paste")
			(net "GND")
			(options
				(clearance outline)
				(anchor circle)
			)
			(primitives
				(gr_poly
					(pts
						(arc
							(start -0.1778 -0.2794)
							(mid -0.249642 -0.249642)
							(end -0.2794 -0.1778)
						)
						(arc
							(start -0.2794 0.1778)
							(mid -0.249642 0.249642)
							(end -0.1778 0.2794)
						)
						(arc
							(start 0.1778 0.2794)
							(mid 0.249642 0.249642)
							(end 0.2794 0.1778)
						)
						(arc
							(start 0.2794 -0.1778)
							(mid 0.249642 -0.249642)
							(end 0.1778 -0.2794)
						)
					)
					(width 0)
					(fill yes)
				)
			)
		)
	)
	(footprint ""
		(layer "F.Cu")
		(at 173.981872 -205.100936 90)
		(property "Reference" "R424"
			(at 0 0 90)
			(layer "F.SilkS")
			(hide yes)
			(effects
				(font
					(size 1.27 1.27)
				)
			)
		)
		(property "Value" "10KR2F-2-GP"
			(at 0.064008 -3.993896 90)
			(unlocked yes)
			(layer "F.Fab")
			(hide yes)
			(effects
				(font
					(size 1.016 1.016)
					(thickness 0.1524)
				)
			)
		)
		(property "Device Type" "R402H16"
			(at 0.064008 -5.517896 90)
			(unlocked yes)
			(layer "F.Fab")
			(hide yes)
			(effects
				(font
					(size 1.016 1.016)
					(thickness 0.1524)
				)
			)
		)
		(duplicate_pad_numbers_are_jumpers no)
		(fp_line
			(start 0.508 -0.9398)
			(end -0.508 -0.9398)
			(stroke
				(width 0.1524)
				(type default)
			)
			(layer "F.SilkS")
		)
		(fp_line
			(start -0.508 -0.9398)
			(end -0.508 0.9398)
			(stroke
				(width 0.1524)
				(type default)
			)
			(layer "F.SilkS")
		)
		(fp_rect
			(start -0.508 0.9398)
			(end 0.508 -0.9398)
			(stroke
				(width 0)
				(type default)
			)
			(fill no)
			(layer "F.CrtYd")
		)
		(fp_rect
			(start -0.508 0.9398)
			(end 0.508 -0.9398)
			(stroke
				(width 0)
				(type default)
			)
			(fill no)
			(layer "F.Fab")
		)
		(pad "1" smd custom
			(at 0 -0.4445 90)
			(size 0.1397 0.1397)
			(layers "F.Cu" "F.Mask" "F.Paste")
			(net "P3V3_STBY")
			(options
				(clearance outline)
				(anchor circle)
			)
			(primitives
				(gr_poly
					(pts
						(arc
							(start -0.1778 -0.2794)
							(mid -0.249642 -0.249642)
							(end -0.2794 -0.1778)
						)
						(arc
							(start -0.2794 0.1778)
							(mid -0.249642 0.249642)
							(end -0.1778 0.2794)
						)
						(arc
							(start 0.1778 0.2794)
							(mid 0.249642 0.249642)
							(end 0.2794 0.1778)
						)
						(arc
							(start 0.2794 -0.1778)
							(mid 0.249642 -0.249642)
							(end 0.1778 -0.2794)
						)
					)
					(width 0)
					(fill yes)
				)
			)
		)
		(pad "2" smd custom
			(at 0 0.4445 90)
			(size 0.1397 0.1397)
			(layers "F.Cu" "F.Mask" "F.Paste")
			(net "I2C_B_BUFF_EN")
			(options
				(clearance outline)
				(anchor circle)
			)
			(primitives
				(gr_poly
					(pts
						(arc
							(start -0.1778 -0.2794)
							(mid -0.249642 -0.249642)
							(end -0.2794 -0.1778)
						)
						(arc
							(start -0.2794 0.1778)
							(mid -0.249642 0.249642)
							(end -0.1778 0.2794)
						)
						(arc
							(start 0.1778 0.2794)
							(mid 0.249642 0.249642)
							(end 0.2794 0.1778)
						)
						(arc
							(start 0.2794 -0.1778)
							(mid 0.249642 -0.249642)
							(end 0.1778 -0.2794)
						)
					)
					(width 0)
					(fill yes)
				)
			)
		)
	)
	(footprint ""
		(layer "F.Cu")
		(at 86.976966 -91.44 180)
		(property "Reference" "SC1201"
			(at 0 0 180)
			(layer "F.SilkS")
			(hide yes)
			(effects
				(font
					(size 1.27 1.27)
				)
			)
		)
		(property "Value" "SCD1U6D3V1KX-GP"
			(at -2.8321 -1.7399 180)
			(unlocked yes)
			(layer "F.Fab")
			(hide yes)
			(effects
				(font
					(size 1.016 1.016)
					(thickness 0.1524)
				)
			)
		)
		(property "Device Type" "C0201H13"
			(at -2.8321 -3.2639 180)
			(unlocked yes)
			(layer "F.Fab")
			(hide yes)
			(effects
				(font
					(size 1.016 1.016)
					(thickness 0.1524)
				)
			)
		)
		(duplicate_pad_numbers_are_jumpers no)
		(fp_rect
			(start -0.2794 0.6477)
			(end 0.2794 -0.6477)
			(stroke
				(width 0)
				(type default)
			)
			(fill no)
			(layer "F.CrtYd")
		)
		(fp_rect
			(start -0.2794 0.6477)
			(end 0.2794 -0.6477)
			(stroke
				(width 0)
				(type default)
			)
			(fill no)
			(layer "F.Fab")
		)
		(pad "1" smd custom
			(at 0 -0.2794 180)
			(size 0.0762 0.0762)
			(layers "F.Cu" "F.Mask" "F.Paste")
			(net "SYSPLL_VDDA09")
			(options
				(clearance outline)
				(anchor circle)
			)
			(primitives
				(gr_poly
					(pts
						(arc
							(start 0.1524 -0.127)
							(mid 0.137521 -0.162921)
							(end 0.1016 -0.1778)
						)
						(arc
							(start -0.1016 -0.1778)
							(mid -0.137521 -0.162921)
							(end -0.1524 -0.127)
						)
						(arc
							(start -0.1524 0.127)
							(mid -0.137521 0.162921)
							(end -0.1016 0.1778)
						)
						(arc
							(start 0.1016 0.1778)
							(mid 0.137521 0.162921)
							(end 0.1524 0.127)
						)
					)
					(width 0)
					(fill yes)
				)
			)
		)
		(pad "2" smd custom
			(at 0 0.2794 180)
			(size 0.0762 0.0762)
			(layers "F.Cu" "F.Mask" "F.Paste")
			(net "GND")
			(options
				(clearance outline)
				(anchor circle)
			)
			(primitives
				(gr_poly
					(pts
						(arc
							(start 0.1524 -0.127)
							(mid 0.137521 -0.162921)
							(end 0.1016 -0.1778)
						)
						(arc
							(start -0.1016 -0.1778)
							(mid -0.137521 -0.162921)
							(end -0.1524 -0.127)
						)
						(arc
							(start -0.1524 0.127)
							(mid -0.137521 0.162921)
							(end -0.1016 0.1778)
						)
						(arc
							(start 0.1016 0.1778)
							(mid 0.137521 0.162921)
							(end 0.1524 0.127)
						)
					)
					(width 0)
					(fill yes)
				)
			)
		)
	)
	(footprint ""
		(layer "F.Cu")
		(at 113.04397 -114.3 180)
		(property "Reference" "SC1077"
			(at 0 0 180)
			(layer "F.SilkS")
			(hide yes)
			(effects
				(font
					(size 1.27 1.27)
				)
			)
		)
		(property "Value" "SCD01U10V1KX-GP"
			(at -2.8321 -1.7399 180)
			(unlocked yes)
			(layer "F.Fab")
			(hide yes)
			(effects
				(font
					(size 1.016 1.016)
					(thickness 0.1524)
				)
			)
		)
		(property "Device Type" "C0201H13"
			(at -2.8321 -3.2639 180)
			(unlocked yes)
			(layer "F.Fab")
			(hide yes)
			(effects
				(font
					(size 1.016 1.016)
					(thickness 0.1524)
				)
			)
		)
		(duplicate_pad_numbers_are_jumpers no)
		(fp_rect
			(start -0.2794 0.6477)
			(end 0.2794 -0.6477)
			(stroke
				(width 0)
				(type default)
			)
			(fill no)
			(layer "F.CrtYd")
		)
		(fp_rect
			(start -0.2794 0.6477)
			(end 0.2794 -0.6477)
			(stroke
				(width 0)
				(type default)
			)
			(fill no)
			(layer "F.Fab")
		)
		(pad "1" smd custom
			(at 0 -0.2794 180)
			(size 0.0762 0.0762)
			(layers "F.Cu" "F.Mask" "F.Paste")
			(net "SAS_HDD_TX5_P")
			(options
				(clearance outline)
				(anchor circle)
			)
			(primitives
				(gr_poly
					(pts
						(arc
							(start 0.1524 -0.127)
							(mid 0.137521 -0.162921)
							(end 0.1016 -0.1778)
						)
						(arc
							(start -0.1016 -0.1778)
							(mid -0.137521 -0.162921)
							(end -0.1524 -0.127)
						)
						(arc
							(start -0.1524 0.127)
							(mid -0.137521 0.162921)
							(end -0.1016 0.1778)
						)
						(arc
							(start 0.1016 0.1778)
							(mid 0.137521 0.162921)
							(end 0.1524 0.127)
						)
					)
					(width 0)
					(fill yes)
				)
			)
		)
		(pad "2" smd custom
			(at 0 0.2794 180)
			(size 0.0762 0.0762)
			(layers "F.Cu" "F.Mask" "F.Paste")
			(net "SAS_EXP_GF_TX_DP9")
			(options
				(clearance outline)
				(anchor circle)
			)
			(primitives
				(gr_poly
					(pts
						(arc
							(start 0.1524 -0.127)
							(mid 0.137521 -0.162921)
							(end 0.1016 -0.1778)
						)
						(arc
							(start -0.1016 -0.1778)
							(mid -0.137521 -0.162921)
							(end -0.1524 -0.127)
						)
						(arc
							(start -0.1524 0.127)
							(mid -0.137521 0.162921)
							(end -0.1016 0.1778)
						)
						(arc
							(start 0.1016 0.1778)
							(mid 0.137521 0.162921)
							(end 0.1524 0.127)
						)
					)
					(width 0)
					(fill yes)
				)
			)
		)
	)
)
